(kicad_pcb
	(version 20260206)
	(generator "pcbnew")
	(generator_version "10.0")
	(general
		(thickness 1.6)
		(legacy_teardrops no)
	)
	(paper "A4")
	(title_block
		(title "03242023_DA0F0TMBIJ0_F0T_Motherboard_J_brd_V01_OCP.brd")
		(comment 1 "Grand Teton / footprint 1682 of 6105 (U1), pads 106-210 of 4677")
	)
	(layers
		(0 "F.Cu" signal "TOP")
		(4 "In1.Cu" signal "GND")
		(6 "In2.Cu" signal "IN1")
		(8 "In3.Cu" signal "GND1")
		(10 "In4.Cu" signal "IN2")
		(12 "In5.Cu" signal "GND2")
		(14 "In6.Cu" signal "IN3")
		(16 "In7.Cu" signal "GND3")
		(18 "In8.Cu" signal "VCC")
		(20 "In9.Cu" signal "VCC1")
		(22 "In10.Cu" signal "GND4")
		(24 "In11.Cu" signal "IN4")
		(26 "In12.Cu" signal "GND5")
		(28 "In13.Cu" signal "IN5")
		(30 "In14.Cu" signal "GND6")
		(32 "In15.Cu" signal "IN6")
		(34 "In16.Cu" signal "GND7")
		(2 "B.Cu" signal "BOTTOM")
		(9 "F.Adhes" user "F.Adhesive")
		(11 "B.Adhes" user "B.Adhesive")
		(13 "F.Paste" user "Package Geometry/Pastemask Top")
		(15 "B.Paste" user "Package Geometry/Pastemask Bottom")
		(5 "F.SilkS" user "Ref Des/Silkscreen Top")
		(7 "B.SilkS" user "Ref Des/Silkscreen Bottom")
		(1 "F.Mask" user "Board Geometry/Soldermask Top")
		(3 "B.Mask" user "Board Geometry/Soldermask Bottom")
		(17 "Dwgs.User" user "User.Drawings")
		(19 "Cmts.User" user "User.Comments")
		(21 "Eco1.User" user "User.Eco1")
		(23 "Eco2.User" user "User.Eco2")
		(25 "Edge.Cuts" user "Board Geometry/Outline")
		(27 "Margin" user)
		(31 "F.CrtYd" user "Package Geometry/Place Bound Top")
		(29 "B.CrtYd" user "Package Geometry/Place Bound Bottom")
		(35 "F.Fab" user "Ref Des/Assembly Top")
		(33 "B.Fab" user "Ref Des/Assembly Bottom")
	)
	(footprint ""
		(layer "F.Cu")
		(at 111.93018 -251.76988 90)
		(property "Reference" "U1"
			(at -74.913236 41.548812 0)
			(unlocked yes)
			(layer "F.SilkS")
			(effects
				(font
					(size 1.6002 1.1938)
					(thickness 0.1524)
				)
				(justify left)
			)
		)
		(property "Value" ""
			(at 0 0 90)
			(layer "F.Fab")
			(effects
				(font
					(size 1.27 1.27)
				)
			)
		)
		(duplicate_pad_numbers_are_jumpers no)
		(pad "AB71" smd circle
			(at 21.147278 -17.096486 270)
			(size 0.4318 0.4318)
			(layers "F.Cu" "F.Mask" "F.Paste")
			(net "GND")
		)
		(pad "AB73" smd circle
			(at 22.77491 -17.096486 270)
			(size 0.4318 0.4318)
			(layers "F.Cu" "F.Mask" "F.Paste")
			(net "M_D_CPU1_SA_DQS_DN<0>")
		)
		(pad "AB75" smd circle
			(at 24.402796 -17.096486 270)
			(size 0.4318 0.4318)
			(layers "F.Cu" "F.Mask" "F.Paste")
			(net "GND")
		)
		(pad "AB77" smd circle
			(at 26.030682 -17.096486 270)
			(size 0.4318 0.4318)
			(layers "F.Cu" "F.Mask" "F.Paste")
			(net "GND")
		)
		(pad "AB79" smd circle
			(at 27.658314 -17.096486 270)
			(size 0.4318 0.4318)
			(layers "F.Cu" "F.Mask" "F.Paste")
			(net "GND")
		)
		(pad "AB81" smd circle
			(at 29.2862 -17.096486 270)
			(size 0.4318 0.4318)
			(layers "F.Cu" "F.Mask" "F.Paste")
			(net "GND")
		)
		(pad "AB83" smd circle
			(at 30.914086 -17.096486 270)
			(size 0.4318 0.4318)
			(layers "F.Cu" "F.Mask" "F.Paste")
			(net "GND")
		)
		(pad "AB85" smd circle
			(at 32.541718 -17.096486 270)
			(size 0.4318 0.4318)
			(layers "F.Cu" "F.Mask" "F.Paste")
			(net "P5E_CPU1_PE4_TX_DP<5>")
		)
		(pad "AB87" smd circle
			(at 34.169604 -17.096486 270)
			(size 0.4318 0.4318)
			(layers "F.Cu" "F.Mask" "F.Paste")
			(net "GND")
		)
		(pad "AB89" smd circle
			(at 35.797236 -17.096486 270)
			(size 0.4318 0.4318)
			(layers "F.Cu" "F.Mask" "F.Paste")
			(net "P5E_CPU1_PE4_RX_DN<5>")
		)
		(pad "AB91" smd oval
			(at 37.425122 -17.096486)
			(size 0.381 0.4826)
			(drill
				(offset 0 -0.0508)
			)
			(layers "F.Cu" "F.Mask" "F.Paste")
			(net "GND")
		)
		(pad "AC1" smd oval
			(at -37.425122 -16.736314 180)
			(size 0.381 0.4826)
			(drill
				(offset 0 -0.0508)
			)
			(layers "F.Cu" "F.Mask" "F.Paste")
			(net "GND")
		)
		(pad "AC3" smd circle
			(at -35.797236 -16.736314 270)
			(size 0.4318 0.4318)
			(layers "F.Cu" "F.Mask" "F.Paste")
			(net "UPI_CPU1_CPU0_P0P1_DP<7>")
		)
		(pad "AC5" smd circle
			(at -34.169604 -16.736314 270)
			(size 0.4318 0.4318)
			(layers "F.Cu" "F.Mask" "F.Paste")
			(net "GND")
		)
		(pad "AC7" smd circle
			(at -32.541718 -16.736314 270)
			(size 0.4318 0.4318)
			(layers "F.Cu" "F.Mask" "F.Paste")
			(net "UPI_CPU0_CPU1_P1P0_DP<6>")
		)
		(pad "AC9" smd circle
			(at -30.914086 -16.736314 270)
			(size 0.4318 0.4318)
			(layers "F.Cu" "F.Mask" "F.Paste")
			(net "GND")
		)
		(pad "AC11" smd circle
			(at -29.2862 -16.736314 270)
			(size 0.4318 0.4318)
			(layers "F.Cu" "F.Mask" "F.Paste")
			(net "P5E_CPU1_PE0_RX_DP<6>")
		)
		(pad "AC13" smd circle
			(at -27.658314 -16.736314 270)
			(size 0.4318 0.4318)
			(layers "F.Cu" "F.Mask" "F.Paste")
			(net "GND")
		)
		(pad "AC15" smd circle
			(at -26.030682 -16.736314 270)
			(size 0.4318 0.4318)
			(layers "F.Cu" "F.Mask" "F.Paste")
			(net "P5E_CPU1_PE0_TX_DP<5>")
		)
		(pad "AC17" smd circle
			(at -24.402796 -16.736314 270)
			(size 0.4318 0.4318)
			(layers "F.Cu" "F.Mask" "F.Paste")
			(net "M_C_CPU1_SB_DQ<30>")
		)
		(pad "AC19" smd circle
			(at -22.77491 -16.736314 270)
			(size 0.4318 0.4318)
			(layers "F.Cu" "F.Mask" "F.Paste")
			(net "M_C_CPU1_SB_DQ<25>")
		)
		(pad "AC21" smd circle
			(at -21.147278 -16.736314 270)
			(size 0.4318 0.4318)
			(layers "F.Cu" "F.Mask" "F.Paste")
			(net "GND")
		)
		(pad "AC23" smd circle
			(at -19.519392 -16.736314 270)
			(size 0.4318 0.4318)
			(layers "F.Cu" "F.Mask" "F.Paste")
			(net "M_D_CPU1_SB_DQ<20>")
		)
		(pad "AC25" smd circle
			(at -17.89176 -16.736314 270)
			(size 0.4318 0.4318)
			(layers "F.Cu" "F.Mask" "F.Paste")
			(net "M_D_CPU1_SB_DQ<17>")
		)
		(pad "AC27" smd circle
			(at -16.263874 -16.736314 270)
			(size 0.4318 0.4318)
			(layers "F.Cu" "F.Mask" "F.Paste")
			(net "GND")
		)
		(pad "AC29" smd circle
			(at -14.635988 -16.736314 270)
			(size 0.4318 0.4318)
			(layers "F.Cu" "F.Mask" "F.Paste")
			(net "M_C_CPU1_SB_DQ<12>")
		)
		(pad "AC31" smd circle
			(at -13.008356 -16.736314 270)
			(size 0.4318 0.4318)
			(layers "F.Cu" "F.Mask" "F.Paste")
			(net "M_C_CPU1_SB_DQ<9>")
		)
		(pad "AC33" smd circle
			(at -11.380724 -16.736314 270)
			(size 0.4318 0.4318)
			(layers "F.Cu" "F.Mask" "F.Paste")
			(net "GND")
		)
		(pad "AC35" smd circle
			(at -9.752838 -16.736314 270)
			(size 0.4318 0.4318)
			(layers "F.Cu" "F.Mask" "F.Paste")
			(net "M_C_CPU1_SB_DQ<4>")
		)
		(pad "AC37" smd circle
			(at -8.124952 -16.736314 270)
			(size 0.4318 0.4318)
			(layers "F.Cu" "F.Mask" "F.Paste")
			(net "M_C_CPU1_SB_DQ<1>")
		)
		(pad "AC39" smd circle
			(at -6.49732 -16.736314 270)
			(size 0.4318 0.4318)
			(layers "F.Cu" "F.Mask" "F.Paste")
			(net "GND")
		)
		(pad "AC41" smd circle
			(at -4.869434 -16.736314 270)
			(size 0.4318 0.4318)
			(layers "F.Cu" "F.Mask" "F.Paste")
			(net "M_D_CPU1_SB_CS_N<0>")
		)
		(pad "AC43" smd circle
			(at -3.241802 -16.736314 270)
			(size 0.4318 0.4318)
			(layers "F.Cu" "F.Mask" "F.Paste")
			(net "M_D_CPU1_SB_CA<4>")
		)
		(pad "AC45" smd circle
			(at -1.613916 -16.736314 270)
			(size 0.4318 0.4318)
			(layers "F.Cu" "F.Mask" "F.Paste")
			(net "GND")
		)
		(pad "AC48" smd circle
			(at 2.427732 -16.626332 270)
			(size 0.4318 0.4318)
			(layers "F.Cu" "F.Mask" "F.Paste")
			(net "M_C_CPU1_SA_RSP<0>")
		)
		(pad "AC50" smd circle
			(at 4.055618 -16.626332 270)
			(size 0.4318 0.4318)
			(layers "F.Cu" "F.Mask" "F.Paste")
			(net "M_D_CPU1_SA_RSP<1>")
		)
		(pad "AC52" smd circle
			(at 5.68325 -16.626332 270)
			(size 0.4318 0.4318)
			(layers "F.Cu" "F.Mask" "F.Paste")
			(net "GND")
		)
		(pad "AC54" smd circle
			(at 7.311136 -16.626332 270)
			(size 0.4318 0.4318)
			(layers "F.Cu" "F.Mask" "F.Paste")
			(net "M_C_CPU1_SA_CB<4>")
		)
		(pad "AC56" smd circle
			(at 8.939022 -16.626332 270)
			(size 0.4318 0.4318)
			(layers "F.Cu" "F.Mask" "F.Paste")
			(net "M_C_CPU1_SA_CB<1>")
		)
		(pad "AC58" smd circle
			(at 10.566654 -16.626332 270)
			(size 0.4318 0.4318)
			(layers "F.Cu" "F.Mask" "F.Paste")
			(net "GND")
		)
		(pad "AC60" smd circle
			(at 12.19454 -16.626332 270)
			(size 0.4318 0.4318)
			(layers "F.Cu" "F.Mask" "F.Paste")
			(net "M_C_CPU1_SA_DQ<28>")
		)
		(pad "AC62" smd circle
			(at 13.822426 -16.626332 270)
			(size 0.4318 0.4318)
			(layers "F.Cu" "F.Mask" "F.Paste")
			(net "M_C_CPU1_SA_DQ<25>")
		)
		(pad "AC64" smd circle
			(at 15.450058 -16.626332 270)
			(size 0.4318 0.4318)
			(layers "F.Cu" "F.Mask" "F.Paste")
			(net "GND")
		)
		(pad "AC66" smd circle
			(at 17.07769 -16.626332 270)
			(size 0.4318 0.4318)
			(layers "F.Cu" "F.Mask" "F.Paste")
			(net "M_C_CPU1_SA_DQ<12>")
		)
		(pad "AC68" smd circle
			(at 18.705576 -16.626332 270)
			(size 0.4318 0.4318)
			(layers "F.Cu" "F.Mask" "F.Paste")
			(net "M_C_CPU1_SA_DQ<9>")
		)
		(pad "AC70" smd circle
			(at 20.333462 -16.626332 270)
			(size 0.4318 0.4318)
			(layers "F.Cu" "F.Mask" "F.Paste")
			(net "GND")
		)
		(pad "AC72" smd circle
			(at 21.961094 -16.626332 270)
			(size 0.4318 0.4318)
			(layers "F.Cu" "F.Mask" "F.Paste")
			(net "M_D_CPU1_SA_DQ<4>")
		)
		(pad "AC74" smd circle
			(at 23.58898 -16.626332 270)
			(size 0.4318 0.4318)
			(layers "F.Cu" "F.Mask" "F.Paste")
			(net "M_D_CPU1_SA_DQ<1>")
		)
		(pad "AC76" smd circle
			(at 25.216612 -16.626332 270)
			(size 0.4318 0.4318)
			(layers "F.Cu" "F.Mask" "F.Paste")
			(net "GND")
		)
		(pad "AC78" smd circle
			(at 26.844498 -16.626332 270)
			(size 0.4318 0.4318)
			(layers "F.Cu" "F.Mask" "F.Paste")
			(net "NC_CPU1_HBM2_VIEWDIG0")
		)
		(pad "AC80" smd circle
			(at 28.472384 -16.626332 270)
			(size 0.4318 0.4318)
			(layers "F.Cu" "F.Mask" "F.Paste")
			(net "UPI_CPU0_CPU1_P2P2_DN<6>")
		)
		(pad "AC82" smd circle
			(at 30.100016 -16.626332 270)
			(size 0.4318 0.4318)
			(layers "F.Cu" "F.Mask" "F.Paste")
			(net "UPI_CPU0_CPU1_P2P2_DP<7>")
		)
		(pad "AC84" smd circle
			(at 31.727902 -16.626332 270)
			(size 0.4318 0.4318)
			(layers "F.Cu" "F.Mask" "F.Paste")
			(net "GND")
		)
		(pad "AC86" smd circle
			(at 33.355534 -16.626332 270)
			(size 0.4318 0.4318)
			(layers "F.Cu" "F.Mask" "F.Paste")
			(net "P5E_CPU1_PE4_TX_DN<6>")
		)
		(pad "AC88" smd circle
			(at 34.98342 -16.626332 270)
			(size 0.4318 0.4318)
			(layers "F.Cu" "F.Mask" "F.Paste")
			(net "GND")
		)
		(pad "AC90" smd circle
			(at 36.611306 -16.626332 270)
			(size 0.4318 0.4318)
			(layers "F.Cu" "F.Mask" "F.Paste")
			(net "P5E_CPU1_PE4_RX_DP<6>")
		)
		(pad "AD2" smd circle
			(at -36.611306 -16.266668 270)
			(size 0.4318 0.4318)
			(layers "F.Cu" "F.Mask" "F.Paste")
			(net "UPI_CPU1_CPU0_P0P1_DN<7>")
		)
		(pad "AD4" smd circle
			(at -34.98342 -16.266668 270)
			(size 0.4318 0.4318)
			(layers "F.Cu" "F.Mask" "F.Paste")
			(net "GND")
		)
		(pad "AD6" smd circle
			(at -33.355534 -16.266668 270)
			(size 0.4318 0.4318)
			(layers "F.Cu" "F.Mask" "F.Paste")
			(net "UPI_CPU0_CPU1_P1P0_DP<7>")
		)
		(pad "AD8" smd circle
			(at -31.727902 -16.266668 270)
			(size 0.4318 0.4318)
			(layers "F.Cu" "F.Mask" "F.Paste")
			(net "GND")
		)
		(pad "AD10" smd circle
			(at -30.100016 -16.266668 270)
			(size 0.4318 0.4318)
			(layers "F.Cu" "F.Mask" "F.Paste")
			(net "P5E_CPU1_PE0_RX_DP<7>")
		)
		(pad "AD12" smd circle
			(at -28.472384 -16.266668 270)
			(size 0.4318 0.4318)
			(layers "F.Cu" "F.Mask" "F.Paste")
			(net "GND")
		)
		(pad "AD14" smd circle
			(at -26.844498 -16.266668 270)
			(size 0.4318 0.4318)
			(layers "F.Cu" "F.Mask" "F.Paste")
			(net "P5E_CPU1_PE0_TX_DP<6>")
		)
		(pad "AD16" smd circle
			(at -25.216612 -16.266668 270)
			(size 0.4318 0.4318)
			(layers "F.Cu" "F.Mask" "F.Paste")
			(net "GND")
		)
		(pad "AD18" smd circle
			(at -23.58898 -16.266668 270)
			(size 0.4318 0.4318)
			(layers "F.Cu" "F.Mask" "F.Paste")
			(net "M_C_CPU1_SB_DQS_DP<3>")
		)
		(pad "AD20" smd circle
			(at -21.961094 -16.266668 270)
			(size 0.4318 0.4318)
			(layers "F.Cu" "F.Mask" "F.Paste")
			(net "M_C_CPU1_SB_DQ<24>")
		)
		(pad "AD22" smd circle
			(at -20.333462 -16.266668 270)
			(size 0.4318 0.4318)
			(layers "F.Cu" "F.Mask" "F.Paste")
			(net "M_D_CPU1_SB_DQ<21>")
		)
		(pad "AD24" smd circle
			(at -18.705576 -16.266668 270)
			(size 0.4318 0.4318)
			(layers "F.Cu" "F.Mask" "F.Paste")
			(net "M_D_CPU1_SB_DQS_DP<2>")
		)
		(pad "AD26" smd circle
			(at -17.07769 -16.266668 270)
			(size 0.4318 0.4318)
			(layers "F.Cu" "F.Mask" "F.Paste")
			(net "M_D_CPU1_SB_DQ<16>")
		)
		(pad "AD28" smd circle
			(at -15.450058 -16.266668 270)
			(size 0.4318 0.4318)
			(layers "F.Cu" "F.Mask" "F.Paste")
			(net "M_C_CPU1_SB_DQ<13>")
		)
		(pad "AD30" smd circle
			(at -13.822426 -16.266668 270)
			(size 0.4318 0.4318)
			(layers "F.Cu" "F.Mask" "F.Paste")
			(net "M_C_CPU1_SB_DQS_DP<1>")
		)
		(pad "AD32" smd circle
			(at -12.19454 -16.266668 270)
			(size 0.4318 0.4318)
			(layers "F.Cu" "F.Mask" "F.Paste")
			(net "M_C_CPU1_SB_DQ<8>")
		)
		(pad "AD34" smd circle
			(at -10.566654 -16.266668 270)
			(size 0.4318 0.4318)
			(layers "F.Cu" "F.Mask" "F.Paste")
			(net "M_C_CPU1_SB_DQ<5>")
		)
		(pad "AD36" smd circle
			(at -8.939022 -16.266668 270)
			(size 0.4318 0.4318)
			(layers "F.Cu" "F.Mask" "F.Paste")
			(net "M_C_CPU1_SB_DQS_DP<0>")
		)
		(pad "AD38" smd circle
			(at -7.311136 -16.266668 270)
			(size 0.4318 0.4318)
			(layers "F.Cu" "F.Mask" "F.Paste")
			(net "M_C_CPU1_SB_DQ<0>")
		)
		(pad "AD40" smd circle
			(at -5.68325 -16.266668 270)
			(size 0.4318 0.4318)
			(layers "F.Cu" "F.Mask" "F.Paste")
			(net "M_D_CPU1_SB_CS_N<3>")
		)
		(pad "AD42" smd circle
			(at -4.055618 -16.266668 270)
			(size 0.4318 0.4318)
			(layers "F.Cu" "F.Mask" "F.Paste")
			(net "GND")
		)
		(pad "AD44" smd circle
			(at -2.427732 -16.266668 270)
			(size 0.4318 0.4318)
			(layers "F.Cu" "F.Mask" "F.Paste")
			(net "M_D_CPU1_SB_CA<2>")
		)
		(pad "AD47" smd circle
			(at 1.613916 -16.156686 270)
			(size 0.4318 0.4318)
			(layers "F.Cu" "F.Mask" "F.Paste")
			(net "M_C_CPU1_SA_RSP<1>")
		)
		(pad "AD49" smd circle
			(at 3.241802 -16.156686 270)
			(size 0.4318 0.4318)
			(layers "F.Cu" "F.Mask" "F.Paste")
			(net "M_C_CPU1_CLK_DP<0>")
		)
		(pad "AD51" smd circle
			(at 4.869434 -16.156686 270)
			(size 0.4318 0.4318)
			(layers "F.Cu" "F.Mask" "F.Paste")
			(net "M_D_CPU1_SA_RSP<0>")
		)
		(pad "AD53" smd circle
			(at 6.49732 -16.156686 270)
			(size 0.4318 0.4318)
			(layers "F.Cu" "F.Mask" "F.Paste")
			(net "M_C_CPU1_SA_CB<5>")
		)
		(pad "AD55" smd circle
			(at 8.124952 -16.156686 270)
			(size 0.4318 0.4318)
			(layers "F.Cu" "F.Mask" "F.Paste")
			(net "M_C_CPU1_SA_DQS_DN<4>")
		)
		(pad "AD57" smd circle
			(at 9.752838 -16.156686 270)
			(size 0.4318 0.4318)
			(layers "F.Cu" "F.Mask" "F.Paste")
			(net "M_C_CPU1_SA_CB<0>")
		)
		(pad "AD59" smd circle
			(at 11.380724 -16.156686 270)
			(size 0.4318 0.4318)
			(layers "F.Cu" "F.Mask" "F.Paste")
			(net "M_C_CPU1_SA_DQ<29>")
		)
		(pad "AD61" smd circle
			(at 13.008356 -16.156686 270)
			(size 0.4318 0.4318)
			(layers "F.Cu" "F.Mask" "F.Paste")
			(net "M_C_CPU1_SA_DQS_DP<3>")
		)
		(pad "AD63" smd circle
			(at 14.635988 -16.156686 270)
			(size 0.4318 0.4318)
			(layers "F.Cu" "F.Mask" "F.Paste")
			(net "M_C_CPU1_SA_DQ<24>")
		)
		(pad "AD65" smd circle
			(at 16.263874 -16.156686 270)
			(size 0.4318 0.4318)
			(layers "F.Cu" "F.Mask" "F.Paste")
			(net "M_C_CPU1_SA_DQ<13>")
		)
		(pad "AD67" smd circle
			(at 17.89176 -16.156686 270)
			(size 0.4318 0.4318)
			(layers "F.Cu" "F.Mask" "F.Paste")
			(net "M_C_CPU1_SA_DQS_DP<1>")
		)
		(pad "AD69" smd circle
			(at 19.519392 -16.156686 270)
			(size 0.4318 0.4318)
			(layers "F.Cu" "F.Mask" "F.Paste")
			(net "M_C_CPU1_SA_DQ<8>")
		)
		(pad "AD71" smd circle
			(at 21.147278 -16.156686 270)
			(size 0.4318 0.4318)
			(layers "F.Cu" "F.Mask" "F.Paste")
			(net "M_D_CPU1_SA_DQ<5>")
		)
		(pad "AD73" smd circle
			(at 22.77491 -16.156686 270)
			(size 0.4318 0.4318)
			(layers "F.Cu" "F.Mask" "F.Paste")
			(net "M_D_CPU1_SA_DQS_DP<0>")
		)
		(pad "AD75" smd circle
			(at 24.402796 -16.156686 270)
			(size 0.4318 0.4318)
			(layers "F.Cu" "F.Mask" "F.Paste")
			(net "M_D_CPU1_SA_DQ<0>")
		)
		(pad "AD77" smd circle
			(at 26.030682 -16.156686 270)
			(size 0.4318 0.4318)
			(layers "F.Cu" "F.Mask" "F.Paste")
			(net "NC_CPU1_HBM2_VIEWDIG1")
		)
		(pad "AD79" smd circle
			(at 27.658314 -16.156686 270)
			(size 0.4318 0.4318)
			(layers "F.Cu" "F.Mask" "F.Paste")
			(net "GND")
		)
		(pad "AD81" smd circle
			(at 29.2862 -16.156686 270)
			(size 0.4318 0.4318)
			(layers "F.Cu" "F.Mask" "F.Paste")
			(net "UPI_CPU0_CPU1_P2P2_DN<7>")
		)
		(pad "AD83" smd circle
			(at 30.914086 -16.156686 270)
			(size 0.4318 0.4318)
			(layers "F.Cu" "F.Mask" "F.Paste")
			(net "GND")
		)
		(pad "AD85" smd circle
			(at 32.541718 -16.156686 270)
			(size 0.4318 0.4318)
			(layers "F.Cu" "F.Mask" "F.Paste")
			(net "PVCCFA_EHV_FIVRA_CPU1")
		)
		(pad "AD87" smd circle
			(at 34.169604 -16.156686 270)
			(size 0.4318 0.4318)
			(layers "F.Cu" "F.Mask" "F.Paste")
			(net "P5E_CPU1_PE4_TX_DP<6>")
		)
		(pad "AD89" smd circle
			(at 35.797236 -16.156686 270)
			(size 0.4318 0.4318)
			(layers "F.Cu" "F.Mask" "F.Paste")
			(net "PVCCFA_EHV_FIVRA_CPU1")
		)
		(pad "AD91" smd oval
			(at 37.425122 -16.156686)
			(size 0.381 0.4826)
			(drill
				(offset 0 -0.0508)
			)
			(layers "F.Cu" "F.Mask" "F.Paste")
			(net "P5E_CPU1_PE4_RX_DN<6>")
		)
		(pad "AE1" smd oval
			(at -37.425122 -15.796514 180)
			(size 0.381 0.4826)
			(drill
				(offset 0 -0.0508)
			)
			(layers "F.Cu" "F.Mask" "F.Paste")
			(net "UPI_CPU1_CPU0_P0P1_DP<8>")
		)
		(pad "AE3" smd circle
			(at -35.797236 -15.796514 270)
			(size 0.4318 0.4318)
			(layers "F.Cu" "F.Mask" "F.Paste")
			(net "PVCCFA_EHV_CPU1")
		)
		(pad "AE5" smd circle
			(at -34.169604 -15.796514 270)
			(size 0.4318 0.4318)
			(layers "F.Cu" "F.Mask" "F.Paste")
			(net "UPI_CPU0_CPU1_P1P0_DN<7>")
		)
		(pad "AE7" smd circle
			(at -32.541718 -15.796514 270)
			(size 0.4318 0.4318)
			(layers "F.Cu" "F.Mask" "F.Paste")
			(net "PVCCFA_EHV_FIVRA_CPU1")
		)
	)
)
